# T6G (Grand Teton) — schematic netlist excerpt (pin names and nets, part order shuffled) for the footprints in the layout excerpt that follows; sources: Cadence DE-HDL packaged netlist, KiCad conversion of 04192023_DAF0TMB3IC0_F0TG_MB_C_brd_V02_OCP.brd

PC130_3  Q_CAP  22UF 4V 20% X6S  pkg C0805  page 202 : A = PVDDCR_CPU1_P0 ; B = GND
C966  Q_CAP  100UF 4V 20% X6S  pkg C0805  page 301 : A = P0V9_CPU0_RT2_2A ; B = GND
PR4540  Q_RES  20K 1% CHIP  pkg 0402LF  page 152 : A = P12V_SCM_ISET ; B = P12V_SCM_ISET_R

(kicad_pcb
	(version 20260206)
	(generator "pcbnew")
	(generator_version "10.0")
	(general
		(thickness 1.6)
		(legacy_teardrops no)
	)
	(paper "A4")
	(title_block
		(title "04192023_DAF0TMB3IC0_F0TG_MB_C_brd_V02_OCP.brd")
		(comment 1 "Grand Teton / footprints 5847-5849 of 8354")
	)
	(layers
		(0 "F.Cu" signal "TOP")
		(4 "In1.Cu" signal "GND")
		(6 "In2.Cu" signal "IN1")
		(8 "In3.Cu" signal "GND1")
		(10 "In4.Cu" signal "IN2")
		(12 "In5.Cu" signal "GND2")
		(14 "In6.Cu" signal "IN3")
		(16 "In7.Cu" signal "GND3")
		(18 "In8.Cu" signal "VCC")
		(20 "In9.Cu" signal "VCC1")
		(22 "In10.Cu" signal "GND4")
		(24 "In11.Cu" signal "IN4")
		(26 "In12.Cu" signal "GND5")
		(28 "In13.Cu" signal "IN5")
		(30 "In14.Cu" signal "GND6")
		(32 "In15.Cu" signal "IN6")
		(34 "In16.Cu" signal "GND7")
		(2 "B.Cu" signal "BOTTOM")
		(9 "F.Adhes" user "F.Adhesive")
		(11 "B.Adhes" user "B.Adhesive")
		(13 "F.Paste" user "Package Geometry/Pastemask Top")
		(15 "B.Paste" user "Package Geometry/Pastemask Bottom")
		(5 "F.SilkS" user "Ref Des/Silkscreen Top")
		(7 "B.SilkS" user "Ref Des/Silkscreen Bottom")
		(1 "F.Mask" user "Board Geometry/Soldermask Top")
		(3 "B.Mask" user "Board Geometry/Soldermask Bottom")
		(17 "Dwgs.User" user "User.Drawings")
		(19 "Cmts.User" user "User.Comments")
		(21 "Eco1.User" user "User.Eco1")
		(23 "Eco2.User" user "User.Eco2")
		(25 "Edge.Cuts" user "Board Geometry/Outline")
		(27 "Margin" user)
		(31 "F.CrtYd" user "Package Geometry/Place Bound Top")
		(29 "B.CrtYd" user "Package Geometry/Place Bound Bottom")
		(35 "F.Fab" user "Ref Des/Assembly Top")
		(33 "B.Fab" user "Ref Des/Assembly Bottom")
	)
	(footprint ""
		(layer "B.Cu")
		(at 398.04721 -398.969484)
		(property "Reference" "C966"
			(at 0 0 0)
			(layer "B.SilkS")
			(hide yes)
			(effects
				(font
					(size 1.27 1.27)
				)
				(justify mirror)
			)
		)
		(property "Value" ""
			(at 0 0 0)
			(layer "B.Fab")
			(effects
				(font
					(size 1.27 1.27)
				)
				(justify mirror)
			)
		)
		(duplicate_pad_numbers_are_jumpers no)
		(fp_line
			(start -1.524 -0.762)
			(end -1.524 0.762)
			(stroke
				(width 0.1524)
				(type default)
			)
			(layer "B.SilkS")
		)
		(fp_line
			(start -1.524 0.762)
			(end 1.524 0.762)
			(stroke
				(width 0.1524)
				(type default)
			)
			(layer "B.SilkS")
		)
		(fp_line
			(start 1.524 -0.762)
			(end -1.524 -0.762)
			(stroke
				(width 0.1524)
				(type default)
			)
			(layer "B.SilkS")
		)
		(fp_line
			(start 1.524 0.762)
			(end 1.524 -0.762)
			(stroke
				(width 0.1524)
				(type default)
			)
			(layer "B.SilkS")
		)
		(fp_line
			(start -1.1049 -0.724916)
			(end 1.1049 -0.724916)
			(stroke
				(width 0.1)
				(type default)
			)
			(layer "B.Fab")
		)
		(fp_line
			(start -1.1049 0.724916)
			(end -1.1049 -0.724916)
			(stroke
				(width 0.1)
				(type default)
			)
			(layer "B.Fab")
		)
		(fp_line
			(start 1.1049 -0.724916)
			(end 1.1049 0.724916)
			(stroke
				(width 0.1)
				(type default)
			)
			(layer "B.Fab")
		)
		(fp_line
			(start 1.1049 0.724916)
			(end -1.1049 0.724916)
			(stroke
				(width 0.1)
				(type default)
			)
			(layer "B.Fab")
		)
		(pad "1" smd rect
			(at 0.889 0)
			(size 1.016 1.27)
			(layers "B.Cu" "B.Mask" "B.Paste")
			(net "P0V9_CPU0_RT2_2A")
		)
		(pad "2" smd rect
			(at -0.889 0)
			(size 1.016 1.27)
			(layers "B.Cu" "B.Mask" "B.Paste")
			(net "GND")
		)
	)
	(footprint ""
		(layer "B.Cu")
		(at 311.733184 -338.082128 -90)
		(property "Reference" "PC130_3"
			(at 0 0 90)
			(layer "B.SilkS")
			(hide yes)
			(effects
				(font
					(size 1.27 1.27)
				)
				(justify mirror)
			)
		)
		(property "Value" ""
			(at 0 0 90)
			(layer "B.Fab")
			(effects
				(font
					(size 1.27 1.27)
				)
				(justify mirror)
			)
		)
		(duplicate_pad_numbers_are_jumpers no)
		(fp_line
			(start -1.524 0.762)
			(end 1.524 0.762)
			(stroke
				(width 0.1524)
				(type default)
			)
			(layer "B.SilkS")
		)
		(fp_line
			(start 1.524 0.762)
			(end 1.524 -0.762)
			(stroke
				(width 0.1524)
				(type default)
			)
			(layer "B.SilkS")
		)
		(fp_line
			(start -1.524 -0.762)
			(end -1.524 0.762)
			(stroke
				(width 0.1524)
				(type default)
			)
			(layer "B.SilkS")
		)
		(fp_line
			(start 1.524 -0.762)
			(end -1.524 -0.762)
			(stroke
				(width 0.1524)
				(type default)
			)
			(layer "B.SilkS")
		)
		(fp_line
			(start -1.1049 0.724916)
			(end -1.1049 -0.724916)
			(stroke
				(width 0.1)
				(type default)
			)
			(layer "B.Fab")
		)
		(fp_line
			(start 1.1049 0.724916)
			(end -1.1049 0.724916)
			(stroke
				(width 0.1)
				(type default)
			)
			(layer "B.Fab")
		)
		(fp_line
			(start -1.1049 -0.724916)
			(end 1.1049 -0.724916)
			(stroke
				(width 0.1)
				(type default)
			)
			(layer "B.Fab")
		)
		(fp_line
			(start 1.1049 -0.724916)
			(end 1.1049 0.724916)
			(stroke
				(width 0.1)
				(type default)
			)
			(layer "B.Fab")
		)
		(pad "1" smd rect
			(at 0.889 0 270)
			(size 1.016 1.27)
			(layers "B.Cu" "B.Mask" "B.Paste")
			(net "PVDDCR_CPU1_P0")
		)
		(pad "2" smd rect
			(at -0.889 0 270)
			(size 1.016 1.27)
			(layers "B.Cu" "B.Mask" "B.Paste")
			(net "GND")
		)
	)
	(footprint ""
		(layer "B.Cu")
		(at 176.264316 -32.137858 -90)
		(property "Reference" "PR4540"
			(at 0 0 90)
			(layer "B.SilkS")
			(hide yes)
			(effects
				(font
					(size 1.27 1.27)
				)
				(justify mirror)
			)
		)
		(property "Value" ""
			(at 0 0 90)
			(layer "B.Fab")
			(effects
				(font
					(size 1.27 1.27)
				)
				(justify mirror)
			)
		)
		(duplicate_pad_numbers_are_jumpers no)
		(fp_line
			(start -0.7874 0.4064)
			(end 0.7874 0.4064)
			(stroke
				(width 0.1524)
				(type default)
			)
			(layer "B.SilkS")
		)
		(fp_line
			(start 0.7874 0.4064)
			(end 0.7874 -0.4064)
			(stroke
				(width 0.1524)
				(type default)
			)
			(layer "B.SilkS")
		)
		(fp_line
			(start -0.7874 -0.4064)
			(end -0.7874 0.4064)
			(stroke
				(width 0.1524)
				(type default)
			)
			(layer "B.SilkS")
		)
		(fp_line
			(start 0.7874 -0.4064)
			(end -0.7874 -0.4064)
			(stroke
				(width 0.1524)
				(type default)
			)
			(layer "B.SilkS")
		)
		(fp_line
			(start -0.67945 0.3048)
			(end -0.120396 0.3048)
			(stroke
				(width 0.1)
				(type default)
			)
			(layer "B.Fab")
		)
		(fp_line
			(start -0.120396 0.3048)
			(end -0.120396 0.2794)
			(stroke
				(width 0.1)
				(type default)
			)
			(layer "B.Fab")
		)
		(fp_line
			(start 0.12065 0.3048)
			(end 0.67945 0.3048)
			(stroke
				(width 0.1)
				(type default)
			)
			(layer "B.Fab")
		)
		(fp_line
			(start 0.67945 0.3048)
			(end 0.67945 -0.305054)
			(stroke
				(width 0.1)
				(type default)
			)
			(layer "B.Fab")
		)
		(fp_line
			(start -0.120396 0.2794)
			(end 0.12065 0.2794)
			(stroke
				(width 0.1)
				(type default)
			)
			(layer "B.Fab")
		)
		(fp_line
			(start 0.12065 0.2794)
			(end 0.12065 0.3048)
			(stroke
				(width 0.1)
				(type default)
			)
			(layer "B.Fab")
		)
		(fp_line
			(start -0.12065 -0.2794)
			(end -0.12065 -0.3048)
			(stroke
				(width 0.1)
				(type default)
			)
			(layer "B.Fab")
		)
		(fp_line
			(start 0.12065 -0.2794)
			(end -0.12065 -0.2794)
			(stroke
				(width 0.1)
				(type default)
			)
			(layer "B.Fab")
		)
		(fp_line
			(start -0.67945 -0.3048)
			(end -0.67945 0.3048)
			(stroke
				(width 0.1)
				(type default)
			)
			(layer "B.Fab")
		)
		(fp_line
			(start -0.12065 -0.3048)
			(end -0.67945 -0.3048)
			(stroke
				(width 0.1)
				(type default)
			)
			(layer "B.Fab")
		)
		(fp_line
			(start 0.12065 -0.305054)
			(end 0.12065 -0.2794)
			(stroke
				(width 0.1)
				(type default)
			)
			(layer "B.Fab")
		)
		(fp_line
			(start 0.67945 -0.305054)
			(end 0.12065 -0.305054)
			(stroke
				(width 0.1)
				(type default)
			)
			(layer "B.Fab")
		)
		(pad "1" smd circle
			(at 0.40005 0 90)
			(size 0 0)
			(layers "B.Cu" "B.Mask" "B.Paste")
			(net "P12V_SCM_ISET")
		)
		(pad "2" smd circle
			(at -0.40005 0 90)
			(size 0 0)
			(layers "B.Cu" "B.Mask" "B.Paste")
			(net "P12V_SCM_ISET_R")
		)
	)
)
